#ISCELL
  pure_quanta quanta_title_block_c *
  *
#ISCELL
  standard offpage *
  page168_i103
#ISCELL
  standard offpage *
  page168_i104
#ISCELL
  standard offpage *
  page168_i107
#ISCELL
  standard offpage *
  page168_i108
#ISCELL
  standard tap *
  page168_i109
#ISCELL
  standard tap *
  page168_i110
#ISCELL
  standard tap *
  page168_i111
#ISCELL
  standard tap *
  page168_i112
#ISCELL
  standard tap *
  page168_i113
#ISCELL
  standard tap *
  page168_i114
#ISCELL
  standard tap *
  page168_i115
#ISCELL
  standard tap *
  page168_i116
#ISCELL
  standard tap *
  page168_i117
#ISCELL
  standard tap *
  page168_i118
#ISCELL
  standard tap *
  page168_i119
#ISCELL
  standard tap *
  page168_i120
#ISCELL
  standard tap *
  page168_i121
#ISCELL
  standard tap *
  page168_i122
#ISCELL
  standard tap *
  page168_i123
#ISCELL
  standard tap *
  page168_i124
#CELL
  pure_quanta q_cap_diffbus *
  page168_i125
#CELL
  pure_quanta q_cap_diffbus *
  page168_i126
#CELL
  pure_quanta q_cap_diffbus *
  page168_i127
#CELL
  pure_quanta q_cap_diffbus *
  page168_i128
#CELL
  pure_quanta q_cap_diffbus *
  page168_i129
#CELL
  pure_quanta q_cap_diffbus *
  page168_i130
#CELL
  pure_quanta q_cap_diffbus *
  page168_i131
#CELL
  pure_quanta q_cap_diffbus *
  page168_i132
#CELL
  pure_quanta q_cap_diffbus *
  page168_i133
#CELL
  pure_quanta q_cap_diffbus *
  page168_i134
#CELL
  pure_quanta q_cap_diffbus *
  page168_i135
#CELL
  pure_quanta q_cap_diffbus *
  page168_i136
#CELL
  pure_quanta q_cap_diffbus *
  page168_i137
#CELL
  pure_quanta q_cap_diffbus *
  page168_i138
#CELL
  pure_quanta q_cap_diffbus *
  page168_i139
#CELL
  pure_quanta q_cap_diffbus *
  page168_i140
#ISCELL
  standard tap *
  page168_i141
#ISCELL
  standard tap *
  page168_i142
#ISCELL
  standard tap *
  page168_i143
#ISCELL
  standard tap *
  page168_i144
#ISCELL
  standard tap *
  page168_i145
#ISCELL
  standard tap *
  page168_i146
#ISCELL
  standard tap *
  page168_i147
#ISCELL
  standard tap *
  page168_i148
#ISCELL
  standard tap *
  page168_i149
#ISCELL
  standard tap *
  page168_i150
#ISCELL
  standard tap *
  page168_i151
#ISCELL
  standard tap *
  page168_i152
#ISCELL
  standard tap *
  page168_i153
#ISCELL
  standard tap *
  page168_i154
#ISCELL
  standard tap *
  page168_i155
#ISCELL
  standard tap *
  page168_i156
#CELL
  pure_quanta q_cap_diffbus *
  page168_i157
#CELL
  pure_quanta q_cap_diffbus *
  page168_i158
#CELL
  pure_quanta q_cap_diffbus *
  page168_i159
#CELL
  pure_quanta q_cap_diffbus *
  page168_i160
#CELL
  pure_quanta q_cap_diffbus *
  page168_i161
#CELL
  pure_quanta q_cap_diffbus *
  page168_i162
#CELL
  pure_quanta q_cap_diffbus *
  page168_i163
#CELL
  pure_quanta q_cap_diffbus *
  page168_i164
#CELL
  pure_quanta q_cap_diffbus *
  page168_i165
#CELL
  pure_quanta q_cap_diffbus *
  page168_i166
#CELL
  pure_quanta q_cap_diffbus *
  page168_i167
#CELL
  pure_quanta q_cap_diffbus *
  page168_i168
#CELL
  pure_quanta q_cap_diffbus *
  page168_i169
#CELL
  pure_quanta q_cap_diffbus *
  page168_i170
#CELL
  pure_quanta q_cap_diffbus *
  page168_i171
#CELL
  pure_quanta q_cap_diffbus *
  page168_i172
#ISCELL
  standard tap *
  page168_i173
#ISCELL
  standard tap *
  page168_i174
#ISCELL
  standard tap *
  page168_i175
#ISCELL
  standard tap *
  page168_i176
#ISCELL
  standard tap *
  page168_i177
#ISCELL
  standard tap *
  page168_i178
#ISCELL
  standard tap *
  page168_i179
#ISCELL
  standard tap *
  page168_i180
#ISCELL
  standard tap *
  page168_i181
#ISCELL
  standard tap *
  page168_i182
#ISCELL
  standard tap *
  page168_i183
#ISCELL
  standard tap *
  page168_i184
#ISCELL
  standard tap *
  page168_i185
#ISCELL
  standard tap *
  page168_i186
#ISCELL
  standard tap *
  page168_i187
#ISCELL
  standard tap *
  page168_i188
#ISCELL
  standard offpage *
  page168_i189
#ISCELL
  standard offpage *
  page168_i190
#ISCELL
  standard tap *
  page168_i191
#ISCELL
  standard tap *
  page168_i192
#ISCELL
  standard tap *
  page168_i193
#ISCELL
  standard tap *
  page168_i194
#ISCELL
  standard tap *
  page168_i195
#ISCELL
  standard tap *
  page168_i196
#ISCELL
  standard tap *
  page168_i197
#ISCELL
  standard tap *
  page168_i198
#ISCELL
  standard tap *
  page168_i199
#ISCELL
  standard tap *
  page168_i200
#ISCELL
  standard tap *
  page168_i201
#ISCELL
  standard tap *
  page168_i202
#ISCELL
  standard tap *
  page168_i203
#ISCELL
  standard tap *
  page168_i204
#ISCELL
  standard tap *
  page168_i205
#ISCELL
  standard tap *
  page168_i206
#ISCELL
  standard offpage *
  page168_i207
#ISCELL
  standard offpage *
  page168_i208
#ISCELL
  standard offpage *
  page168_i209
#ISCELL
  standard offpage *
  page168_i210
#ISCELL
  standard offpage *
  page168_i211
#ISCELL
  standard offpage *
  page168_i212
#ISCELL
  standard tap *
  page168_i213
#ISCELL
  standard tap *
  page168_i214
#ISCELL
  standard tap *
  page168_i215
#ISCELL
  standard tap *
  page168_i216
#ISCELL
  standard tap *
  page168_i217
#ISCELL
  standard tap *
  page168_i218
#ISCELL
  standard tap *
  page168_i219
#ISCELL
  standard tap *
  page168_i220
#ISCELL
  standard tap *
  page168_i221
#ISCELL
  standard tap *
  page168_i222
#ISCELL
  standard tap *
  page168_i223
#ISCELL
  standard tap *
  page168_i224
#ISCELL
  standard tap *
  page168_i225
#ISCELL
  standard tap *
  page168_i226
#ISCELL
  standard tap *
  page168_i227
#ISCELL
  standard tap *
  page168_i228
#CELL
  pure_quanta q_cap_diffbus *
  page168_i229
#CELL
  pure_quanta q_cap_diffbus *
  page168_i230
#CELL
  pure_quanta q_cap_diffbus *
  page168_i231
#CELL
  pure_quanta q_cap_diffbus *
  page168_i232
#CELL
  pure_quanta q_cap_diffbus *
  page168_i233
#CELL
  pure_quanta q_cap_diffbus *
  page168_i234
#CELL
  pure_quanta q_cap_diffbus *
  page168_i235
#CELL
  pure_quanta q_cap_diffbus *
  page168_i236
#CELL
  pure_quanta q_cap_diffbus *
  page168_i237
#CELL
  pure_quanta q_cap_diffbus *
  page168_i238
#ISCELL
  standard tap *
  page168_i239
#ISCELL
  standard tap *
  page168_i240
#ISCELL
  standard tap *
  page168_i241
#ISCELL
  standard tap *
  page168_i242
#ISCELL
  standard tap *
  page168_i243
#ISCELL
  standard tap *
  page168_i244
#ISCELL
  standard tap *
  page168_i245
#ISCELL
  standard tap *
  page168_i246
#ISCELL
  standard tap *
  page168_i247
#ISCELL
  standard tap *
  page168_i248
#CELL
  pure_quanta q_cap_diffbus *
  page168_i249
#CELL
  pure_quanta q_cap_diffbus *
  page168_i250
#CELL
  pure_quanta q_cap_diffbus *
  page168_i251
#CELL
  pure_quanta q_cap_diffbus *
  page168_i252
#CELL
  pure_quanta q_cap_diffbus *
  page168_i253
#CELL
  pure_quanta q_cap_diffbus *
  page168_i254
#ISCELL
  standard tap *
  page168_i255
#ISCELL
  standard tap *
  page168_i256
#ISCELL
  standard tap *
  page168_i257
#ISCELL
  standard tap *
  page168_i258
#ISCELL
  standard tap *
  page168_i259
#ISCELL
  standard tap *
  page168_i260
#ISCELL
  standard tap *
  page168_i261
#ISCELL
  standard tap *
  page168_i262
#ISCELL
  standard tap *
  page168_i263
#ISCELL
  standard tap *
  page168_i264
#ISCELL
  standard tap *
  page168_i265
#ISCELL
  standard tap *
  page168_i266
#ISCELL
  standard tap *
  page168_i267
#ISCELL
  standard tap *
  page168_i268
#ISCELL
  standard tap *
  page168_i269
#ISCELL
  standard tap *
  page168_i270
#ISCELL
  standard tap *
  page168_i271
#ISCELL
  standard tap *
  page168_i272
#ISCELL
  standard tap *
  page168_i273
#ISCELL
  standard tap *
  page168_i274
#ISCELL
  standard tap *
  page168_i275
#ISCELL
  standard tap *
  page168_i276
#CELL
  pure_quanta q_cap_diffbus *
  page168_i277
#CELL
  pure_quanta q_cap_diffbus *
  page168_i278
#CELL
  pure_quanta q_cap_diffbus *
  page168_i279
#CELL
  pure_quanta q_cap_diffbus *
  page168_i280
#CELL
  pure_quanta q_cap_diffbus *
  page168_i281
#CELL
  pure_quanta q_cap_diffbus *
  page168_i282
#CELL
  pure_quanta q_cap_diffbus *
  page168_i283
#CELL
  pure_quanta q_cap_diffbus *
  page168_i284
#CELL
  pure_quanta q_cap_diffbus *
  page168_i285
#CELL
  pure_quanta q_cap_diffbus *
  page168_i286
#ISCELL
  standard tap *
  page168_i287
#ISCELL
  standard tap *
  page168_i288
#ISCELL
  standard tap *
  page168_i289
#ISCELL
  standard tap *
  page168_i290
#ISCELL
  standard tap *
  page168_i291
#ISCELL
  standard tap *
  page168_i292
#ISCELL
  standard tap *
  page168_i293
#ISCELL
  standard tap *
  page168_i294
#ISCELL
  standard tap *
  page168_i295
#ISCELL
  standard tap *
  page168_i296
#CELL
  pure_quanta q_cap_diffbus *
  page168_i297
#CELL
  pure_quanta q_cap_diffbus *
  page168_i298
#CELL
  pure_quanta q_cap_diffbus *
  page168_i299
#CELL
  pure_quanta q_cap_diffbus *
  page168_i300
#CELL
  pure_quanta q_cap_diffbus *
  page168_i301
#CELL
  pure_quanta q_cap_diffbus *
  page168_i302
#ISCELL
  standard tap *
  page168_i303
#ISCELL
  standard tap *
  page168_i304
#ISCELL
  standard tap *
  page168_i305
#ISCELL
  standard tap *
  page168_i306
#ISCELL
  standard tap *
  page168_i307
#ISCELL
  standard tap *
  page168_i308
#ISCELL
  standard offpage *
  page168_i309
#ISCELL
  standard offpage *
  page168_i310
#ISCELL
  standard offpage *
  page168_i311
#ISCELL
  standard offpage *
  page168_i312
